(kicad_pcb
	(version 20260206)
	(generator "pcbnew")
	(generator_version "10.0")
	(general
		(thickness 1.6)
		(legacy_teardrops no)
	)
	(paper "A4")
	(title_block
		(title "04192023_DAF0TMB3IC0_F0TG_MB_C_brd_V02_OCP.brd")
		(comment 1 "Grand Teton / footprints 3548-3551 of 8354")
	)
	(layers
		(0 "F.Cu" signal "TOP")
		(4 "In1.Cu" signal "GND")
		(6 "In2.Cu" signal "IN1")
		(8 "In3.Cu" signal "GND1")
		(10 "In4.Cu" signal "IN2")
		(12 "In5.Cu" signal "GND2")
		(14 "In6.Cu" signal "IN3")
		(16 "In7.Cu" signal "GND3")
		(18 "In8.Cu" signal "VCC")
		(20 "In9.Cu" signal "VCC1")
		(22 "In10.Cu" signal "GND4")
		(24 "In11.Cu" signal "IN4")
		(26 "In12.Cu" signal "GND5")
		(28 "In13.Cu" signal "IN5")
		(30 "In14.Cu" signal "GND6")
		(32 "In15.Cu" signal "IN6")
		(34 "In16.Cu" signal "GND7")
		(2 "B.Cu" signal "BOTTOM")
		(9 "F.Adhes" user "F.Adhesive")
		(11 "B.Adhes" user "B.Adhesive")
		(13 "F.Paste" user "Package Geometry/Pastemask Top")
		(15 "B.Paste" user "Package Geometry/Pastemask Bottom")
		(5 "F.SilkS" user "Ref Des/Silkscreen Top")
		(7 "B.SilkS" user "Ref Des/Silkscreen Bottom")
		(1 "F.Mask" user "Board Geometry/Soldermask Top")
		(3 "B.Mask" user "Board Geometry/Soldermask Bottom")
		(17 "Dwgs.User" user "User.Drawings")
		(19 "Cmts.User" user "User.Comments")
		(21 "Eco1.User" user "User.Eco1")
		(23 "Eco2.User" user "User.Eco2")
		(25 "Edge.Cuts" user "Board Geometry/Outline")
		(27 "Margin" user)
		(31 "F.CrtYd" user "Package Geometry/Place Bound Top")
		(29 "B.CrtYd" user "Package Geometry/Place Bound Bottom")
		(35 "F.Fab" user "Ref Des/Assembly Top")
		(33 "B.Fab" user "Ref Des/Assembly Bottom")
	)
	(footprint ""
		(layer "F.Cu")
		(at 335.05902 -334.973676)
		(property "Reference" "PU13"
			(at -2.95402 -7.772654 0)
			(unlocked yes)
			(layer "F.SilkS")
			(effects
				(font
					(size 0.7874 0.5842)
					(thickness 0.1524)
				)
				(justify left)
			)
		)
		(property "Value" ""
			(at 0 0 0)
			(layer "F.Fab")
			(effects
				(font
					(size 1.27 1.27)
				)
			)
		)
		(duplicate_pad_numbers_are_jumpers no)
		(fp_line
			(start -2.500122 -2.999994)
			(end -2.24409 -2.999994)
			(stroke
				(width 0.1524)
				(type default)
			)
			(layer "F.SilkS")
		)
		(fp_line
			(start -2.500122 -2.529078)
			(end -2.500122 -2.999994)
			(stroke
				(width 0.1524)
				(type default)
			)
			(layer "F.SilkS")
		)
		(fp_line
			(start -2.500122 0.6604)
			(end -2.500122 0.229108)
			(stroke
				(width 0.1524)
				(type default)
			)
			(layer "F.SilkS")
		)
		(fp_line
			(start -2.500122 2.999994)
			(end -2.500122 2.339594)
			(stroke
				(width 0.1524)
				(type default)
			)
			(layer "F.SilkS")
		)
		(fp_line
			(start -2.2987 2.999994)
			(end -2.500122 2.999994)
			(stroke
				(width 0.1524)
				(type default)
			)
			(layer "F.SilkS")
		)
		(fp_line
			(start 2.31394 -2.999994)
			(end 2.500122 -2.999994)
			(stroke
				(width 0.1524)
				(type default)
			)
			(layer "F.SilkS")
		)
		(fp_line
			(start 2.500122 -2.999994)
			(end 2.500122 -2.44348)
			(stroke
				(width 0.1524)
				(type default)
			)
			(layer "F.SilkS")
		)
		(fp_line
			(start 2.500122 2.339594)
			(end 2.500122 2.999994)
			(stroke
				(width 0.1524)
				(type default)
			)
			(layer "F.SilkS")
		)
		(fp_line
			(start 2.500122 2.999994)
			(end 2.2987 2.999994)
			(stroke
				(width 0.1524)
				(type default)
			)
			(layer "F.SilkS")
		)
		(fp_poly
			(pts
				(xy -2.77114 -2.42824) (xy -3.444748 -2.652776) (xy -2.995676 -3.101848)
			)
			(stroke
				(width 0)
				(type default)
			)
			(fill yes)
			(layer "F.SilkS")
		)
		(fp_line
			(start -2.500122 -2.999994)
			(end 2.500122 -2.999994)
			(stroke
				(width 0.1)
				(type default)
			)
			(layer "F.Fab")
		)
		(fp_line
			(start -2.500122 2.999994)
			(end -2.500122 -2.999994)
			(stroke
				(width 0.1)
				(type default)
			)
			(layer "F.Fab")
		)
		(fp_line
			(start 2.500122 -2.999994)
			(end 2.500122 2.999994)
			(stroke
				(width 0.1)
				(type default)
			)
			(layer "F.Fab")
		)
		(fp_line
			(start 2.500122 2.999994)
			(end -2.500122 2.999994)
			(stroke
				(width 0.1)
				(type default)
			)
			(layer "F.Fab")
		)
		(fp_poly
			(pts
				(xy -4.218432 -2.783078) (xy -4.218432 -1.767078) (xy -3.202432 -2.275078)
			)
			(stroke
				(width 0)
				(type default)
			)
			(fill yes)
			(layer "F.Fab")
		)
		(pad "1" smd rect
			(at -2.400046 -2.275078 90)
			(size 0.2286 0.6096)
			(layers "F.Cu" "F.Mask" "F.Paste")
			(net "PVDDCR_CPU1_P0_VOS1")
		)
		(pad "2" smd rect
			(at -2.400046 -1.82499 90)
			(size 0.2286 0.6096)
			(layers "F.Cu" "F.Mask" "F.Paste")
			(net "GND")
		)
		(pad "3" smd rect
			(at -2.400046 -1.374902 90)
			(size 0.2286 0.6096)
			(layers "F.Cu" "F.Mask" "F.Paste")
			(net "PVDDCR_CPU1_P0_VCC1")
		)
		(pad "4" smd rect
			(at -2.400046 -0.925068 90)
			(size 0.2286 0.6096)
			(layers "F.Cu" "F.Mask" "F.Paste")
			(net "PVDDCR_CPU1_P0_PVCC")
		)
		(pad "5" smd rect
			(at -2.400046 -0.47498 90)
			(size 0.2286 0.6096)
			(layers "F.Cu" "F.Mask" "F.Paste")
			(net "GND")
		)
		(pad "6" smd rect
			(at -2.400046 -0.024892 90)
			(size 0.2286 0.6096)
			(layers "F.Cu" "F.Mask" "F.Paste")
			(net "NC_PVDDCR_CPU1_P0_GL1_1")
		)
		(pad "7_9-20_24" smd circle
			(at 0 1.150112 90)
			(size 0 0)
			(layers "F.Cu" "F.Mask" "F.Paste")
			(net "GND")
		)
		(pad "10_19" smd rect
			(at 0 2.899918 90)
			(size 0.6096 4.318)
			(layers "F.Cu" "F.Mask" "F.Paste")
			(net "SW_PVDDCR_CPU1_P0_SW1")
		)
		(pad "25_29" smd rect
			(at 1.549908 -1.279906 270)
			(size 2.0574 2.3114)
			(layers "F.Cu" "F.Mask" "F.Paste")
			(net "SW_P12V_AUX_PVDDCR_CPU1_P0_FLT")
		)
		(pad "30" smd rect
			(at 2.05994 -2.899918)
			(size 0.2286 0.6096)
			(layers "F.Cu" "F.Mask" "F.Paste")
			(net "SW_P12V_AUX_PVDDCR_CPU1_P0_FLT")
		)
		(pad "31" smd rect
			(at 1.610106 -2.899918)
			(size 0.2286 0.6096)
			(layers "F.Cu" "F.Mask" "F.Paste")
			(net "NC_PVDDCR_CPU1_P0_DNC1")
		)
		(pad "32" smd rect
			(at 1.160018 -2.899918)
			(size 0.2286 0.6096)
			(layers "F.Cu" "F.Mask" "F.Paste")
			(net "SW_PVDDCR_CPU1_P0_BOOTR1")
		)
		(pad "33" smd rect
			(at 0.70993 -2.899918)
			(size 0.2286 0.6096)
			(layers "F.Cu" "F.Mask" "F.Paste")
			(net "SW_PVDDCR_CPU1_P0_BOOT1")
		)
		(pad "34" smd rect
			(at 0.260096 -2.899918)
			(size 0.2286 0.6096)
			(layers "F.Cu" "F.Mask" "F.Paste")
			(net "PVDDCR_CPU1_P0_PWM1")
		)
		(pad "35" smd rect
			(at -0.189992 -2.899918)
			(size 0.2286 0.6096)
			(layers "F.Cu" "F.Mask" "F.Paste")
			(net "PVDDCR_CPU1_P0_VCC1")
		)
		(pad "36" smd rect
			(at -0.64008 -2.899918)
			(size 0.2286 0.6096)
			(layers "F.Cu" "F.Mask" "F.Paste")
			(net "PVDDCR_CPU1_P0_TEMP0")
		)
		(pad "37" smd rect
			(at -1.089914 -2.899918)
			(size 0.2286 0.6096)
			(layers "F.Cu" "F.Mask" "F.Paste")
			(net "PVDDCR_CPU1_P0_LSET1")
		)
		(pad "38" smd rect
			(at -1.540002 -2.899918)
			(size 0.2286 0.6096)
			(layers "F.Cu" "F.Mask" "F.Paste")
			(net "PVDDCR_CPU1_P0_IMON1")
		)
		(pad "39" smd rect
			(at -1.99009 -2.899918)
			(size 0.2286 0.6096)
			(layers "F.Cu" "F.Mask" "F.Paste")
			(net "PVDDCR_CPU1_P0_VCCS")
		)
		(pad "40" smd rect
			(at -0.87503 -1.27508)
			(size 1.7526 1.9558)
			(layers "F.Cu" "F.Mask" "F.Paste")
			(net "GND")
		)
		(pad "41" smd rect
			(at -1.525016 0.249936 270)
			(size 0.3048 0.4572)
			(layers "F.Cu" "F.Mask" "F.Paste")
			(net "NC_PVDDCR_CPU1_P0_GL2_1")
		)
		(zone
			(layer "F.Cu")
			(hatch none 0.5)
			(connect_pads
				(clearance 0)
			)
			(min_thickness 0.25)
			(keepout
				(tracks not_allowed)
				(vias allowed)
				(pads allowed)
				(copperpour not_allowed)
				(footprints allowed)
			)
			(placement
				(enabled no)
				(sheetname "")
			)
			(fill
				(thermal_gap 0.5)
				(thermal_bridge_width 0.5)
				(island_removal_mode 0)
			)
			(polygon
				(pts
					(xy 332.558898 -332.3971) (xy 332.558898 -332.722982) (xy 337.559142 -332.722982) (xy 337.559142 -332.41234)
					(xy 337.26882 -332.41234) (xy 337.26882 -332.429358) (xy 332.84922 -332.429358) (xy 332.84922 -332.3971)
				)
			)
		)
		(zone
			(layer "F.Cu")
			(hatch none 0.5)
			(connect_pads
				(clearance 0)
			)
			(min_thickness 0.25)
			(keepout
				(tracks not_allowed)
				(vias allowed)
				(pads allowed)
				(copperpour not_allowed)
				(footprints allowed)
			)
			(placement
				(enabled no)
				(sheetname "")
			)
			(fill
				(thermal_gap 0.5)
				(thermal_bridge_width 0.5)
				(island_removal_mode 0)
			)
			(polygon
				(pts
					(xy 335.11109 -335.220056) (xy 335.11109 -337.277456) (xy 333.25689 -337.277456) (xy 333.25689 -337.03641)
					(xy 333.014574 -337.03641) (xy 333.014574 -337.517994) (xy 336.841846 -337.517994) (xy 336.841846 -337.333082)
					(xy 335.402428 -337.333082) (xy 335.402428 -335.174082) (xy 337.559142 -335.174082) (xy 337.559142 -334.9244)
					(xy 335.406746 -334.9244)
				)
			)
		)
	)
	(footprint ""
		(layer "F.Cu")
		(at 102.75697 -182.694834 90)
		(property "Reference" "PC288_C0P1_3"
			(at 0 0 90)
			(layer "F.SilkS")
			(hide yes)
			(effects
				(font
					(size 1.27 1.27)
				)
			)
		)
		(property "Value" ""
			(at 0 0 90)
			(layer "F.Fab")
			(effects
				(font
					(size 1.27 1.27)
				)
			)
		)
		(duplicate_pad_numbers_are_jumpers no)
		(fp_line
			(start 0.7874 -0.4064)
			(end 0.7874 0.4064)
			(stroke
				(width 0.1524)
				(type default)
			)
			(layer "F.SilkS")
		)
		(fp_line
			(start -0.7874 -0.4064)
			(end 0.7874 -0.4064)
			(stroke
				(width 0.1524)
				(type default)
			)
			(layer "F.SilkS")
		)
		(fp_line
			(start 0.7874 0.4064)
			(end -0.7874 0.4064)
			(stroke
				(width 0.1524)
				(type default)
			)
			(layer "F.SilkS")
		)
		(fp_line
			(start -0.7874 0.4064)
			(end -0.7874 -0.4064)
			(stroke
				(width 0.1524)
				(type default)
			)
			(layer "F.SilkS")
		)
		(fp_line
			(start -0.12065 -0.305054)
			(end -0.12065 -0.2794)
			(stroke
				(width 0.1)
				(type default)
			)
			(layer "F.Fab")
		)
		(fp_line
			(start -0.67945 -0.305054)
			(end -0.12065 -0.305054)
			(stroke
				(width 0.1)
				(type default)
			)
			(layer "F.Fab")
		)
		(fp_line
			(start 0.67945 -0.3048)
			(end 0.67945 0.3048)
			(stroke
				(width 0.1)
				(type default)
			)
			(layer "F.Fab")
		)
		(fp_line
			(start 0.12065 -0.3048)
			(end 0.67945 -0.3048)
			(stroke
				(width 0.1)
				(type default)
			)
			(layer "F.Fab")
		)
		(fp_line
			(start 0.12065 -0.2794)
			(end 0.12065 -0.3048)
			(stroke
				(width 0.1)
				(type default)
			)
			(layer "F.Fab")
		)
		(fp_line
			(start -0.12065 -0.2794)
			(end 0.12065 -0.2794)
			(stroke
				(width 0.1)
				(type default)
			)
			(layer "F.Fab")
		)
		(fp_line
			(start 0.120396 0.2794)
			(end -0.12065 0.2794)
			(stroke
				(width 0.1)
				(type default)
			)
			(layer "F.Fab")
		)
		(fp_line
			(start -0.12065 0.2794)
			(end -0.12065 0.3048)
			(stroke
				(width 0.1)
				(type default)
			)
			(layer "F.Fab")
		)
		(fp_line
			(start 0.67945 0.3048)
			(end 0.120396 0.3048)
			(stroke
				(width 0.1)
				(type default)
			)
			(layer "F.Fab")
		)
		(fp_line
			(start 0.120396 0.3048)
			(end 0.120396 0.2794)
			(stroke
				(width 0.1)
				(type default)
			)
			(layer "F.Fab")
		)
		(fp_line
			(start -0.12065 0.3048)
			(end -0.67945 0.3048)
			(stroke
				(width 0.1)
				(type default)
			)
			(layer "F.Fab")
		)
		(fp_line
			(start -0.67945 0.3048)
			(end -0.67945 -0.305054)
			(stroke
				(width 0.1)
				(type default)
			)
			(layer "F.Fab")
		)
		(pad "1" smd circle
			(at -0.40005 0 90)
			(size 0 0)
			(layers "F.Cu" "F.Mask" "F.Paste")
			(net "PVDDCR_CPU0_P1_PVCC")
		)
		(pad "2" smd circle
			(at 0.40005 0 90)
			(size 0 0)
			(layers "F.Cu" "F.Mask" "F.Paste")
			(net "GND")
		)
	)
	(footprint ""
		(layer "F.Cu")
		(at 169.38879 -103.31577 90)
		(property "Reference" "R6185"
			(at 0 0 90)
			(layer "F.SilkS")
			(hide yes)
			(effects
				(font
					(size 1.27 1.27)
				)
			)
		)
		(property "Value" ""
			(at 0 0 90)
			(layer "F.Fab")
			(effects
				(font
					(size 1.27 1.27)
				)
			)
		)
		(duplicate_pad_numbers_are_jumpers no)
		(fp_line
			(start 0.7874 -0.4064)
			(end 0.7874 0.4064)
			(stroke
				(width 0.1524)
				(type default)
			)
			(layer "F.SilkS")
		)
		(fp_line
			(start -0.7874 -0.4064)
			(end 0.7874 -0.4064)
			(stroke
				(width 0.1524)
				(type default)
			)
			(layer "F.SilkS")
		)
		(fp_line
			(start 0.7874 0.4064)
			(end -0.7874 0.4064)
			(stroke
				(width 0.1524)
				(type default)
			)
			(layer "F.SilkS")
		)
		(fp_line
			(start -0.7874 0.4064)
			(end -0.7874 -0.4064)
			(stroke
				(width 0.1524)
				(type default)
			)
			(layer "F.SilkS")
		)
		(fp_line
			(start -0.12065 -0.305054)
			(end -0.12065 -0.2794)
			(stroke
				(width 0.1)
				(type default)
			)
			(layer "F.Fab")
		)
		(fp_line
			(start -0.67945 -0.305054)
			(end -0.12065 -0.305054)
			(stroke
				(width 0.1)
				(type default)
			)
			(layer "F.Fab")
		)
		(fp_line
			(start 0.67945 -0.3048)
			(end 0.67945 0.3048)
			(stroke
				(width 0.1)
				(type default)
			)
			(layer "F.Fab")
		)
		(fp_line
			(start 0.12065 -0.3048)
			(end 0.67945 -0.3048)
			(stroke
				(width 0.1)
				(type default)
			)
			(layer "F.Fab")
		)
		(fp_line
			(start 0.12065 -0.2794)
			(end 0.12065 -0.3048)
			(stroke
				(width 0.1)
				(type default)
			)
			(layer "F.Fab")
		)
		(fp_line
			(start -0.12065 -0.2794)
			(end 0.12065 -0.2794)
			(stroke
				(width 0.1)
				(type default)
			)
			(layer "F.Fab")
		)
		(fp_line
			(start 0.120396 0.2794)
			(end -0.12065 0.2794)
			(stroke
				(width 0.1)
				(type default)
			)
			(layer "F.Fab")
		)
		(fp_line
			(start -0.12065 0.2794)
			(end -0.12065 0.3048)
			(stroke
				(width 0.1)
				(type default)
			)
			(layer "F.Fab")
		)
		(fp_line
			(start 0.67945 0.3048)
			(end 0.120396 0.3048)
			(stroke
				(width 0.1)
				(type default)
			)
			(layer "F.Fab")
		)
		(fp_line
			(start 0.120396 0.3048)
			(end 0.120396 0.2794)
			(stroke
				(width 0.1)
				(type default)
			)
			(layer "F.Fab")
		)
		(fp_line
			(start -0.12065 0.3048)
			(end -0.67945 0.3048)
			(stroke
				(width 0.1)
				(type default)
			)
			(layer "F.Fab")
		)
		(fp_line
			(start -0.67945 0.3048)
			(end -0.67945 -0.305054)
			(stroke
				(width 0.1)
				(type default)
			)
			(layer "F.Fab")
		)
		(pad "1" smd circle
			(at -0.40005 0 90)
			(size 0 0)
			(layers "F.Cu" "F.Mask" "F.Paste")
			(net "FM_SEC_MUX_OE_N")
		)
		(pad "2" smd circle
			(at 0.40005 0 90)
			(size 0 0)
			(layers "F.Cu" "F.Mask" "F.Paste")
			(net "GND")
		)
	)
	(footprint ""
		(layer "F.Cu")
		(at 208.894426 -105.497376)
		(property "Reference" "R6051"
			(at 0 0 0)
			(layer "F.SilkS")
			(hide yes)
			(effects
				(font
					(size 1.27 1.27)
				)
			)
		)
		(property "Value" ""
			(at 0 0 0)
			(layer "F.Fab")
			(effects
				(font
					(size 1.27 1.27)
				)
			)
		)
		(duplicate_pad_numbers_are_jumpers no)
		(fp_line
			(start -0.7874 -0.4064)
			(end 0.7874 -0.4064)
			(stroke
				(width 0.1524)
				(type default)
			)
			(layer "F.SilkS")
		)
		(fp_line
			(start -0.7874 0.4064)
			(end -0.7874 -0.4064)
			(stroke
				(width 0.1524)
				(type default)
			)
			(layer "F.SilkS")
		)
		(fp_line
			(start 0.7874 -0.4064)
			(end 0.7874 0.4064)
			(stroke
				(width 0.1524)
				(type default)
			)
			(layer "F.SilkS")
		)
		(fp_line
			(start 0.7874 0.4064)
			(end -0.7874 0.4064)
			(stroke
				(width 0.1524)
				(type default)
			)
			(layer "F.SilkS")
		)
		(fp_line
			(start -0.67945 -0.305054)
			(end -0.12065 -0.305054)
			(stroke
				(width 0.1)
				(type default)
			)
			(layer "F.Fab")
		)
		(fp_line
			(start -0.67945 0.3048)
			(end -0.67945 -0.305054)
			(stroke
				(width 0.1)
				(type default)
			)
			(layer "F.Fab")
		)
		(fp_line
			(start -0.12065 -0.305054)
			(end -0.12065 -0.2794)
			(stroke
				(width 0.1)
				(type default)
			)
			(layer "F.Fab")
		)
		(fp_line
			(start -0.12065 -0.2794)
			(end 0.12065 -0.2794)
			(stroke
				(width 0.1)
				(type default)
			)
			(layer "F.Fab")
		)
		(fp_line
			(start -0.12065 0.2794)
			(end -0.12065 0.3048)
			(stroke
				(width 0.1)
				(type default)
			)
			(layer "F.Fab")
		)
		(fp_line
			(start -0.12065 0.3048)
			(end -0.67945 0.3048)
			(stroke
				(width 0.1)
				(type default)
			)
			(layer "F.Fab")
		)
		(fp_line
			(start 0.120396 0.2794)
			(end -0.12065 0.2794)
			(stroke
				(width 0.1)
				(type default)
			)
			(layer "F.Fab")
		)
		(fp_line
			(start 0.120396 0.3048)
			(end 0.120396 0.2794)
			(stroke
				(width 0.1)
				(type default)
			)
			(layer "F.Fab")
		)
		(fp_line
			(start 0.12065 -0.3048)
			(end 0.67945 -0.3048)
			(stroke
				(width 0.1)
				(type default)
			)
			(layer "F.Fab")
		)
		(fp_line
			(start 0.12065 -0.2794)
			(end 0.12065 -0.3048)
			(stroke
				(width 0.1)
				(type default)
			)
			(layer "F.Fab")
		)
		(fp_line
			(start 0.67945 -0.3048)
			(end 0.67945 0.3048)
			(stroke
				(width 0.1)
				(type default)
			)
			(layer "F.Fab")
		)
		(fp_line
			(start 0.67945 0.3048)
			(end 0.120396 0.3048)
			(stroke
				(width 0.1)
				(type default)
			)
			(layer "F.Fab")
		)
		(pad "1" smd circle
			(at -0.40005 0)
			(size 0 0)
			(layers "F.Cu" "F.Mask" "F.Paste")
			(net "P12V_OCP_V3_1_PWRGD")
		)
		(pad "2" smd circle
			(at 0.40005 0)
			(size 0 0)
			(layers "F.Cu" "F.Mask" "F.Paste")
			(net "P12V_OCP_V3_1_PLD_PWRGD")
		)
	)
)
